(kicad_pcb
	(version 20260206)
	(generator "pcbnew")
	(generator_version "10.0")
	(general
		(thickness 1.6)
		(legacy_teardrops no)
	)
	(paper "A4")
	(title_block
		(title "01162023_DA0F0TEBIF0_F0T_Expander_BD_F_brd_V02_OCP.brd")
		(comment 1 "Grand Teton / footprints 3308-3313 of 9728")
	)
	(layers
		(0 "F.Cu" signal "TOP")
		(4 "In1.Cu" signal "GND")
		(6 "In2.Cu" signal "VCC")
		(8 "In3.Cu" signal "VCC1")
		(10 "In4.Cu" signal "GND1")
		(12 "In5.Cu" signal "IN1")
		(14 "In6.Cu" signal "GND2")
		(16 "In7.Cu" signal "IN2")
		(18 "In8.Cu" signal "GND3")
		(20 "In9.Cu" signal "IN3")
		(22 "In10.Cu" signal "GND4")
		(24 "In11.Cu" signal "IN4")
		(26 "In12.Cu" signal "GND5")
		(28 "In13.Cu" signal "IN5")
		(30 "In14.Cu" signal "GND6")
		(32 "In15.Cu" signal "IN6")
		(34 "In16.Cu" signal "GND7")
		(2 "B.Cu" signal "BOTTOM")
		(9 "F.Adhes" user "F.Adhesive")
		(11 "B.Adhes" user "B.Adhesive")
		(13 "F.Paste" user "Package Geometry/Pastemask Top")
		(15 "B.Paste" user "Package Geometry/Pastemask Bottom")
		(5 "F.SilkS" user "Ref Des/Silkscreen Top")
		(7 "B.SilkS" user "Ref Des/Silkscreen Bottom")
		(1 "F.Mask" user "Board Geometry/Soldermask Top")
		(3 "B.Mask" user "Board Geometry/Soldermask Bottom")
		(17 "Dwgs.User" user "User.Drawings")
		(19 "Cmts.User" user "User.Comments")
		(21 "Eco1.User" user "User.Eco1")
		(23 "Eco2.User" user "User.Eco2")
		(25 "Edge.Cuts" user "Board Geometry/Outline")
		(27 "Margin" user)
		(31 "F.CrtYd" user "Package Geometry/Place Bound Top")
		(29 "B.CrtYd" user "Package Geometry/Place Bound Bottom")
		(35 "F.Fab" user "Ref Des/Assembly Top")
		(33 "B.Fab" user "Ref Des/Assembly Bottom")
	)
	(footprint ""
		(layer "F.Cu")
		(at 126.249684 -148.872702)
		(property "Reference" "PD82"
			(at -3.4544 -2.225548 0)
			(unlocked yes)
			(layer "F.SilkS")
			(effects
				(font
					(size 0.7874 0.5842)
					(thickness 0.1524)
				)
				(justify left)
			)
		)
		(property "Value" ""
			(at 0 0 0)
			(layer "F.Fab")
			(effects
				(font
					(size 1.27 1.27)
				)
			)
		)
		(duplicate_pad_numbers_are_jumpers no)
		(fp_line
			(start -3.400044 -1.459992)
			(end 4.107942 -1.459992)
			(stroke
				(width 0.1524)
				(type default)
			)
			(layer "F.SilkS")
		)
		(fp_line
			(start -3.400044 1.459992)
			(end -3.400044 -1.459992)
			(stroke
				(width 0.1524)
				(type default)
			)
			(layer "F.SilkS")
		)
		(fp_line
			(start 4.107942 -1.459992)
			(end 4.107942 1.459992)
			(stroke
				(width 0.1524)
				(type default)
			)
			(layer "F.SilkS")
		)
		(fp_line
			(start 4.107942 1.459992)
			(end -3.400044 1.459992)
			(stroke
				(width 0.1524)
				(type default)
			)
			(layer "F.SilkS")
		)
		(fp_poly
			(pts
				(xy 4.107942 -1.459992) (xy 4.107942 1.459992) (xy 3.308096 1.459992) (xy 3.308096 -1.459992)
			)
			(stroke
				(width 0)
				(type default)
			)
			(fill yes)
			(layer "F.SilkS")
		)
		(fp_line
			(start -2.29997 -1.459992)
			(end 2.29997 -1.459992)
			(stroke
				(width 0.1)
				(type default)
			)
			(layer "F.Fab")
		)
		(fp_line
			(start -2.29997 1.459992)
			(end -2.29997 -1.459992)
			(stroke
				(width 0.1)
				(type default)
			)
			(layer "F.Fab")
		)
		(fp_line
			(start 2.29997 -1.459992)
			(end 2.29997 1.459992)
			(stroke
				(width 0.1)
				(type default)
			)
			(layer "F.Fab")
		)
		(fp_line
			(start 2.29997 1.459992)
			(end -2.29997 1.459992)
			(stroke
				(width 0.1)
				(type default)
			)
			(layer "F.Fab")
		)
		(fp_text user "+"
			(at -4.7752 -0.12065 0)
			(unlocked yes)
			(layer "F.SilkS")
			(effects
				(font
					(size 1.905 1.4224)
					(thickness 0.1524)
				)
				(justify left)
			)
		)
		(fp_text user "-"
			(at 5.4102 0.29845 180)
			(unlocked yes)
			(layer "F.SilkS")
			(effects
				(font
					(size 1.905 1.4224)
					(thickness 0.1524)
				)
				(justify left)
			)
		)
		(fp_text user "+"
			(at -4.7752 -0.12065 0)
			(unlocked yes)
			(layer "F.Fab")
			(effects
				(font
					(size 1.905 1.4224)
					(thickness 0.1524)
				)
				(justify left)
			)
		)
		(fp_text user "-"
			(at 5.4102 0.29845 180)
			(unlocked yes)
			(layer "F.Fab")
			(effects
				(font
					(size 1.905 1.4224)
					(thickness 0.1524)
				)
				(justify left)
			)
		)
		(pad "A" smd rect
			(at -1.999996 0 90)
			(size 1.7018 2.5146)
			(layers "F.Cu" "F.Mask" "F.Paste")
			(net "GND")
		)
		(pad "C" smd rect
			(at 1.999996 0 90)
			(size 1.7018 2.5146)
			(layers "F.Cu" "F.Mask" "F.Paste")
			(net "P12V_NIC2_R")
		)
	)
	(footprint ""
		(layer "F.Cu")
		(at 410.91739 -390.996932 180)
		(property "Reference" "C4158"
			(at 0 0 180)
			(layer "F.SilkS")
			(hide yes)
			(effects
				(font
					(size 1.27 1.27)
				)
			)
		)
		(property "Value" ""
			(at 0 0 180)
			(layer "F.Fab")
			(effects
				(font
					(size 1.27 1.27)
				)
			)
		)
		(duplicate_pad_numbers_are_jumpers no)
		(fp_line
			(start 0.7874 0.4064)
			(end -0.7874 0.4064)
			(stroke
				(width 0.1524)
				(type default)
			)
			(layer "F.SilkS")
		)
		(fp_line
			(start 0.7874 -0.4064)
			(end 0.7874 0.4064)
			(stroke
				(width 0.1524)
				(type default)
			)
			(layer "F.SilkS")
		)
		(fp_line
			(start -0.7874 0.4064)
			(end -0.7874 -0.4064)
			(stroke
				(width 0.1524)
				(type default)
			)
			(layer "F.SilkS")
		)
		(fp_line
			(start -0.7874 -0.4064)
			(end 0.7874 -0.4064)
			(stroke
				(width 0.1524)
				(type default)
			)
			(layer "F.SilkS")
		)
		(fp_line
			(start 0.67945 0.3048)
			(end 0.120396 0.3048)
			(stroke
				(width 0.1)
				(type default)
			)
			(layer "F.Fab")
		)
		(fp_line
			(start 0.67945 -0.3048)
			(end 0.67945 0.3048)
			(stroke
				(width 0.1)
				(type default)
			)
			(layer "F.Fab")
		)
		(fp_line
			(start 0.12065 -0.2794)
			(end 0.12065 -0.3048)
			(stroke
				(width 0.1)
				(type default)
			)
			(layer "F.Fab")
		)
		(fp_line
			(start 0.12065 -0.3048)
			(end 0.67945 -0.3048)
			(stroke
				(width 0.1)
				(type default)
			)
			(layer "F.Fab")
		)
		(fp_line
			(start 0.120396 0.3048)
			(end 0.120396 0.2794)
			(stroke
				(width 0.1)
				(type default)
			)
			(layer "F.Fab")
		)
		(fp_line
			(start 0.120396 0.2794)
			(end -0.12065 0.2794)
			(stroke
				(width 0.1)
				(type default)
			)
			(layer "F.Fab")
		)
		(fp_line
			(start -0.12065 0.3048)
			(end -0.67945 0.3048)
			(stroke
				(width 0.1)
				(type default)
			)
			(layer "F.Fab")
		)
		(fp_line
			(start -0.12065 0.2794)
			(end -0.12065 0.3048)
			(stroke
				(width 0.1)
				(type default)
			)
			(layer "F.Fab")
		)
		(fp_line
			(start -0.12065 -0.2794)
			(end 0.12065 -0.2794)
			(stroke
				(width 0.1)
				(type default)
			)
			(layer "F.Fab")
		)
		(fp_line
			(start -0.12065 -0.305054)
			(end -0.12065 -0.2794)
			(stroke
				(width 0.1)
				(type default)
			)
			(layer "F.Fab")
		)
		(fp_line
			(start -0.67945 0.3048)
			(end -0.67945 -0.305054)
			(stroke
				(width 0.1)
				(type default)
			)
			(layer "F.Fab")
		)
		(fp_line
			(start -0.67945 -0.305054)
			(end -0.12065 -0.305054)
			(stroke
				(width 0.1)
				(type default)
			)
			(layer "F.Fab")
		)
		(pad "1" smd circle
			(at -0.40005 0 180)
			(size 0 0)
			(layers "F.Cu" "F.Mask" "F.Paste")
			(net "GND")
		)
		(pad "2" smd circle
			(at 0.40005 0 180)
			(size 0 0)
			(layers "F.Cu" "F.Mask" "F.Paste")
			(net "GPU_BB_RSVD_1")
		)
	)
	(footprint ""
		(layer "F.Cu")
		(at 376.795284 -35.48253)
		(property "Reference" "U394"
			(at -2.550414 0.83693 90)
			(unlocked yes)
			(layer "F.SilkS")
			(effects
				(font
					(size 0.7874 0.5842)
					(thickness 0.1524)
				)
				(justify left)
			)
		)
		(property "Value" ""
			(at 0 0 0)
			(layer "F.Fab")
			(effects
				(font
					(size 1.27 1.27)
				)
			)
		)
		(duplicate_pad_numbers_are_jumpers no)
		(fp_line
			(start -1.3462 -1.1938)
			(end -1.3462 1.1684)
			(stroke
				(width 0.1524)
				(type default)
			)
			(layer "F.SilkS")
		)
		(fp_line
			(start -1.3462 1.1938)
			(end 1.3462 1.1938)
			(stroke
				(width 0.1524)
				(type default)
			)
			(layer "F.SilkS")
		)
		(fp_line
			(start 1.3462 -1.1938)
			(end -1.3462 -1.1938)
			(stroke
				(width 0.1524)
				(type default)
			)
			(layer "F.SilkS")
		)
		(fp_line
			(start 1.3462 1.1938)
			(end 1.3462 -1.1938)
			(stroke
				(width 0.1524)
				(type default)
			)
			(layer "F.SilkS")
		)
		(fp_poly
			(pts
				(xy -1.447038 -0.760476) (xy -2.052066 -0.457962) (xy -2.052066 -1.06299)
			)
			(stroke
				(width 0)
				(type default)
			)
			(fill yes)
			(layer "F.SilkS")
		)
		(fp_line
			(start -0.674878 -1.124966)
			(end -0.674878 1.124966)
			(stroke
				(width 0.1)
				(type default)
			)
			(layer "F.Fab")
		)
		(fp_line
			(start -0.674878 1.124966)
			(end 0.674878 1.124966)
			(stroke
				(width 0.1)
				(type default)
			)
			(layer "F.Fab")
		)
		(fp_line
			(start 0.674878 -1.124966)
			(end -0.674878 -1.124966)
			(stroke
				(width 0.1)
				(type default)
			)
			(layer "F.Fab")
		)
		(fp_line
			(start 0.674878 1.124966)
			(end 0.674878 -1.124966)
			(stroke
				(width 0.1)
				(type default)
			)
			(layer "F.Fab")
		)
		(fp_poly
			(pts
				(xy -1.447038 -0.760476) (xy -2.052066 -0.457962) (xy -2.052066 -1.06299)
			)
			(stroke
				(width 0)
				(type default)
			)
			(fill yes)
			(layer "F.Fab")
		)
		(pad "1" smd rect
			(at -0.899922 -0.750062)
			(size 0.6096 0.6096)
			(layers "F.Cu" "F.Mask" "F.Paste")
			(net "PWRGD_P3V3_SSD13_R")
		)
		(pad "2" smd rect
			(at -0.899922 0 90)
			(size 0.4064 0.6096)
			(layers "F.Cu" "F.Mask" "F.Paste")
			(net "RST_SMB_SSD13_N")
		)
		(pad "3" smd rect
			(at -0.899922 0.750062)
			(size 0.6096 0.6096)
			(layers "F.Cu" "F.Mask" "F.Paste")
			(net "GND")
		)
		(pad "4" smd rect
			(at 0.899922 0.750062)
			(size 0.6096 0.6096)
			(layers "F.Cu" "F.Mask" "F.Paste")
			(net "RST_SMB_SSD13_ISO_N")
		)
		(pad "5" smd rect
			(at 0.899922 -0.750062)
			(size 0.6096 0.6096)
			(layers "F.Cu" "F.Mask" "F.Paste")
			(net "P3V3_AUX")
		)
	)
	(footprint ""
		(layer "F.Cu")
		(at 376.312684 -84.2518)
		(property "Reference" "R1747"
			(at 0 0 0)
			(layer "F.SilkS")
			(hide yes)
			(effects
				(font
					(size 1.27 1.27)
				)
			)
		)
		(property "Value" ""
			(at 0 0 0)
			(layer "F.Fab")
			(effects
				(font
					(size 1.27 1.27)
				)
			)
		)
		(duplicate_pad_numbers_are_jumpers no)
		(fp_line
			(start -0.7874 -0.4064)
			(end 0.7874 -0.4064)
			(stroke
				(width 0.1524)
				(type default)
			)
			(layer "F.SilkS")
		)
		(fp_line
			(start -0.7874 0.4064)
			(end -0.7874 -0.4064)
			(stroke
				(width 0.1524)
				(type default)
			)
			(layer "F.SilkS")
		)
		(fp_line
			(start 0.7874 -0.4064)
			(end 0.7874 0.4064)
			(stroke
				(width 0.1524)
				(type default)
			)
			(layer "F.SilkS")
		)
		(fp_line
			(start 0.7874 0.4064)
			(end -0.7874 0.4064)
			(stroke
				(width 0.1524)
				(type default)
			)
			(layer "F.SilkS")
		)
		(fp_line
			(start -0.67945 -0.305054)
			(end -0.12065 -0.305054)
			(stroke
				(width 0.1)
				(type default)
			)
			(layer "F.Fab")
		)
		(fp_line
			(start -0.67945 0.3048)
			(end -0.67945 -0.305054)
			(stroke
				(width 0.1)
				(type default)
			)
			(layer "F.Fab")
		)
		(fp_line
			(start -0.12065 -0.305054)
			(end -0.12065 -0.2794)
			(stroke
				(width 0.1)
				(type default)
			)
			(layer "F.Fab")
		)
		(fp_line
			(start -0.12065 -0.2794)
			(end 0.12065 -0.2794)
			(stroke
				(width 0.1)
				(type default)
			)
			(layer "F.Fab")
		)
		(fp_line
			(start -0.12065 0.2794)
			(end -0.12065 0.3048)
			(stroke
				(width 0.1)
				(type default)
			)
			(layer "F.Fab")
		)
		(fp_line
			(start -0.12065 0.3048)
			(end -0.67945 0.3048)
			(stroke
				(width 0.1)
				(type default)
			)
			(layer "F.Fab")
		)
		(fp_line
			(start 0.120396 0.2794)
			(end -0.12065 0.2794)
			(stroke
				(width 0.1)
				(type default)
			)
			(layer "F.Fab")
		)
		(fp_line
			(start 0.120396 0.3048)
			(end 0.120396 0.2794)
			(stroke
				(width 0.1)
				(type default)
			)
			(layer "F.Fab")
		)
		(fp_line
			(start 0.12065 -0.3048)
			(end 0.67945 -0.3048)
			(stroke
				(width 0.1)
				(type default)
			)
			(layer "F.Fab")
		)
		(fp_line
			(start 0.12065 -0.2794)
			(end 0.12065 -0.3048)
			(stroke
				(width 0.1)
				(type default)
			)
			(layer "F.Fab")
		)
		(fp_line
			(start 0.67945 -0.3048)
			(end 0.67945 0.3048)
			(stroke
				(width 0.1)
				(type default)
			)
			(layer "F.Fab")
		)
		(fp_line
			(start 0.67945 0.3048)
			(end 0.120396 0.3048)
			(stroke
				(width 0.1)
				(type default)
			)
			(layer "F.Fab")
		)
		(pad "1" smd circle
			(at -0.40005 0)
			(size 0 0)
			(layers "F.Cu" "F.Mask" "F.Paste")
			(net "P3V3_AUX")
		)
		(pad "2" smd circle
			(at 0.40005 0)
			(size 0 0)
			(layers "F.Cu" "F.Mask" "F.Paste")
			(net "SMB_BIC_I2C6_MUX_THERMAL_R_SDA")
		)
	)
	(footprint ""
		(layer "F.Cu")
		(at 251.472954 -207.097122 90)
		(property "Reference" "C2494"
			(at 0 0 90)
			(layer "F.SilkS")
			(hide yes)
			(effects
				(font
					(size 1.27 1.27)
				)
			)
		)
		(property "Value" ""
			(at 0 0 90)
			(layer "F.Fab")
			(effects
				(font
					(size 1.27 1.27)
				)
			)
		)
		(duplicate_pad_numbers_are_jumpers no)
		(fp_line
			(start 0.7874 -0.4064)
			(end 0.7874 0.4064)
			(stroke
				(width 0.1524)
				(type default)
			)
			(layer "F.SilkS")
		)
		(fp_line
			(start -0.7874 -0.4064)
			(end 0.7874 -0.4064)
			(stroke
				(width 0.1524)
				(type default)
			)
			(layer "F.SilkS")
		)
		(fp_line
			(start 0.7874 0.4064)
			(end -0.7874 0.4064)
			(stroke
				(width 0.1524)
				(type default)
			)
			(layer "F.SilkS")
		)
		(fp_line
			(start -0.7874 0.4064)
			(end -0.7874 -0.4064)
			(stroke
				(width 0.1524)
				(type default)
			)
			(layer "F.SilkS")
		)
		(fp_line
			(start -0.12065 -0.305054)
			(end -0.12065 -0.2794)
			(stroke
				(width 0.1)
				(type default)
			)
			(layer "F.Fab")
		)
		(fp_line
			(start -0.67945 -0.305054)
			(end -0.12065 -0.305054)
			(stroke
				(width 0.1)
				(type default)
			)
			(layer "F.Fab")
		)
		(fp_line
			(start 0.67945 -0.3048)
			(end 0.67945 0.3048)
			(stroke
				(width 0.1)
				(type default)
			)
			(layer "F.Fab")
		)
		(fp_line
			(start 0.12065 -0.3048)
			(end 0.67945 -0.3048)
			(stroke
				(width 0.1)
				(type default)
			)
			(layer "F.Fab")
		)
		(fp_line
			(start 0.12065 -0.2794)
			(end 0.12065 -0.3048)
			(stroke
				(width 0.1)
				(type default)
			)
			(layer "F.Fab")
		)
		(fp_line
			(start -0.12065 -0.2794)
			(end 0.12065 -0.2794)
			(stroke
				(width 0.1)
				(type default)
			)
			(layer "F.Fab")
		)
		(fp_line
			(start 0.120396 0.2794)
			(end -0.12065 0.2794)
			(stroke
				(width 0.1)
				(type default)
			)
			(layer "F.Fab")
		)
		(fp_line
			(start -0.12065 0.2794)
			(end -0.12065 0.3048)
			(stroke
				(width 0.1)
				(type default)
			)
			(layer "F.Fab")
		)
		(fp_line
			(start 0.67945 0.3048)
			(end 0.120396 0.3048)
			(stroke
				(width 0.1)
				(type default)
			)
			(layer "F.Fab")
		)
		(fp_line
			(start 0.120396 0.3048)
			(end 0.120396 0.2794)
			(stroke
				(width 0.1)
				(type default)
			)
			(layer "F.Fab")
		)
		(fp_line
			(start -0.12065 0.3048)
			(end -0.67945 0.3048)
			(stroke
				(width 0.1)
				(type default)
			)
			(layer "F.Fab")
		)
		(fp_line
			(start -0.67945 0.3048)
			(end -0.67945 -0.305054)
			(stroke
				(width 0.1)
				(type default)
			)
			(layer "F.Fab")
		)
		(pad "1" smd circle
			(at -0.40005 0 90)
			(size 0 0)
			(layers "F.Cu" "F.Mask" "F.Paste")
			(net "P3V3_AUX")
		)
		(pad "2" smd circle
			(at 0.40005 0 90)
			(size 0 0)
			(layers "F.Cu" "F.Mask" "F.Paste")
			(net "GND")
		)
	)
	(footprint ""
		(layer "F.Cu")
		(at 32.411416 -290.044632 -90)
		(property "Reference" "R4562"
			(at 0 0 270)
			(layer "F.SilkS")
			(hide yes)
			(effects
				(font
					(size 1.27 1.27)
				)
			)
		)
		(property "Value" ""
			(at 0 0 270)
			(layer "F.Fab")
			(effects
				(font
					(size 1.27 1.27)
				)
			)
		)
		(duplicate_pad_numbers_are_jumpers no)
		(fp_line
			(start -0.7874 0.4064)
			(end -0.7874 -0.4064)
			(stroke
				(width 0.1524)
				(type default)
			)
			(layer "F.SilkS")
		)
		(fp_line
			(start 0.7874 0.4064)
			(end -0.7874 0.4064)
			(stroke
				(width 0.1524)
				(type default)
			)
			(layer "F.SilkS")
		)
		(fp_line
			(start -0.7874 -0.4064)
			(end 0.7874 -0.4064)
			(stroke
				(width 0.1524)
				(type default)
			)
			(layer "F.SilkS")
		)
		(fp_line
			(start 0.7874 -0.4064)
			(end 0.7874 0.4064)
			(stroke
				(width 0.1524)
				(type default)
			)
			(layer "F.SilkS")
		)
		(fp_line
			(start -0.67945 0.3048)
			(end -0.67945 -0.305054)
			(stroke
				(width 0.1)
				(type default)
			)
			(layer "F.Fab")
		)
		(fp_line
			(start -0.12065 0.3048)
			(end -0.67945 0.3048)
			(stroke
				(width 0.1)
				(type default)
			)
			(layer "F.Fab")
		)
		(fp_line
			(start 0.120396 0.3048)
			(end 0.120396 0.2794)
			(stroke
				(width 0.1)
				(type default)
			)
			(layer "F.Fab")
		)
		(fp_line
			(start 0.67945 0.3048)
			(end 0.120396 0.3048)
			(stroke
				(width 0.1)
				(type default)
			)
			(layer "F.Fab")
		)
		(fp_line
			(start -0.12065 0.2794)
			(end -0.12065 0.3048)
			(stroke
				(width 0.1)
				(type default)
			)
			(layer "F.Fab")
		)
		(fp_line
			(start 0.120396 0.2794)
			(end -0.12065 0.2794)
			(stroke
				(width 0.1)
				(type default)
			)
			(layer "F.Fab")
		)
		(fp_line
			(start -0.12065 -0.2794)
			(end 0.12065 -0.2794)
			(stroke
				(width 0.1)
				(type default)
			)
			(layer "F.Fab")
		)
		(fp_line
			(start 0.12065 -0.2794)
			(end 0.12065 -0.3048)
			(stroke
				(width 0.1)
				(type default)
			)
			(layer "F.Fab")
		)
		(fp_line
			(start 0.12065 -0.3048)
			(end 0.67945 -0.3048)
			(stroke
				(width 0.1)
				(type default)
			)
			(layer "F.Fab")
		)
		(fp_line
			(start 0.67945 -0.3048)
			(end 0.67945 0.3048)
			(stroke
				(width 0.1)
				(type default)
			)
			(layer "F.Fab")
		)
		(fp_line
			(start -0.67945 -0.305054)
			(end -0.12065 -0.305054)
			(stroke
				(width 0.1)
				(type default)
			)
			(layer "F.Fab")
		)
		(fp_line
			(start -0.12065 -0.305054)
			(end -0.12065 -0.2794)
			(stroke
				(width 0.1)
				(type default)
			)
			(layer "F.Fab")
		)
		(pad "1" smd circle
			(at -0.40005 0 270)
			(size 0 0)
			(layers "F.Cu" "F.Mask" "F.Paste")
			(net "PCEPLL4_VDDA18_PEX0")
		)
		(pad "2" smd circle
			(at 0.40005 0 270)
			(size 0 0)
			(layers "F.Cu" "F.Mask" "F.Paste")
			(net "PCEPLL4_VDDA18_PEX0_R")
		)
	)
)
